# S9S_MB_2U (Grand Teton) — schematic netlist excerpt (pin names and nets, part order shuffled) for the footprints in the layout excerpt that follows; sources: Cadence DE-HDL packaged netlist, KiCad conversion of 03242023_DA0F0TMBIJ0_F0T_Motherboard_J_brd_V01_OCP.brd

R3190  Q_RES  4.7K 1% CHIP  pkg 0402LF  page 161 : A = P3V3_AUX ; B = OCP_V3_2_PWRBRK_BUFF_N
C746  Q_CAP_DIFFBUS  DIFF BUS_0.22UF 6.3V 20% X6S  pkg C0201  page 176 : \1\ = P5E_CPU1_PE2_TX_C_DN<13> ; \2\ = P5E_CPU1_PE2_TX_DN<13>

(kicad_pcb
	(version 20260206)
	(generator "pcbnew")
	(generator_version "10.0")
	(general
		(thickness 1.6)
		(legacy_teardrops no)
	)
	(paper "A4")
	(title_block
		(title "03242023_DA0F0TMBIJ0_F0T_Motherboard_J_brd_V01_OCP.brd")
		(comment 1 "Grand Teton / footprints 1172-1173 of 6105")
	)
	(layers
		(0 "F.Cu" signal "TOP")
		(4 "In1.Cu" signal "GND")
		(6 "In2.Cu" signal "IN1")
		(8 "In3.Cu" signal "GND1")
		(10 "In4.Cu" signal "IN2")
		(12 "In5.Cu" signal "GND2")
		(14 "In6.Cu" signal "IN3")
		(16 "In7.Cu" signal "GND3")
		(18 "In8.Cu" signal "VCC")
		(20 "In9.Cu" signal "VCC1")
		(22 "In10.Cu" signal "GND4")
		(24 "In11.Cu" signal "IN4")
		(26 "In12.Cu" signal "GND5")
		(28 "In13.Cu" signal "IN5")
		(30 "In14.Cu" signal "GND6")
		(32 "In15.Cu" signal "IN6")
		(34 "In16.Cu" signal "GND7")
		(2 "B.Cu" signal "BOTTOM")
		(9 "F.Adhes" user "F.Adhesive")
		(11 "B.Adhes" user "B.Adhesive")
		(13 "F.Paste" user "Package Geometry/Pastemask Top")
		(15 "B.Paste" user "Package Geometry/Pastemask Bottom")
		(5 "F.SilkS" user "Ref Des/Silkscreen Top")
		(7 "B.SilkS" user "Ref Des/Silkscreen Bottom")
		(1 "F.Mask" user "Board Geometry/Soldermask Top")
		(3 "B.Mask" user "Board Geometry/Soldermask Bottom")
		(17 "Dwgs.User" user "User.Drawings")
		(19 "Cmts.User" user "User.Comments")
		(21 "Eco1.User" user "User.Eco1")
		(23 "Eco2.User" user "User.Eco2")
		(25 "Edge.Cuts" user "Board Geometry/Outline")
		(27 "Margin" user)
		(31 "F.CrtYd" user "Package Geometry/Place Bound Top")
		(29 "B.CrtYd" user "Package Geometry/Place Bound Bottom")
		(35 "F.Fab" user "Ref Des/Assembly Top")
		(33 "B.Fab" user "Ref Des/Assembly Bottom")
	)
	(footprint ""
		(layer "F.Cu")
		(at 116.367306 -30.720792 180)
		(property "Reference" "R3190"
			(at 0 0 180)
			(layer "F.SilkS")
			(hide yes)
			(effects
				(font
					(size 1.27 1.27)
				)
			)
		)
		(property "Value" ""
			(at 0 0 180)
			(layer "F.Fab")
			(effects
				(font
					(size 1.27 1.27)
				)
			)
		)
		(duplicate_pad_numbers_are_jumpers no)
		(fp_line
			(start 0.7874 0.4064)
			(end -0.7874 0.4064)
			(stroke
				(width 0.1524)
				(type default)
			)
			(layer "F.SilkS")
		)
		(fp_line
			(start 0.7874 -0.4064)
			(end 0.7874 0.4064)
			(stroke
				(width 0.1524)
				(type default)
			)
			(layer "F.SilkS")
		)
		(fp_line
			(start -0.7874 0.4064)
			(end -0.7874 -0.4064)
			(stroke
				(width 0.1524)
				(type default)
			)
			(layer "F.SilkS")
		)
		(fp_line
			(start -0.7874 -0.4064)
			(end 0.7874 -0.4064)
			(stroke
				(width 0.1524)
				(type default)
			)
			(layer "F.SilkS")
		)
		(fp_line
			(start 0.67945 0.3048)
			(end 0.120396 0.3048)
			(stroke
				(width 0.1)
				(type default)
			)
			(layer "F.Fab")
		)
		(fp_line
			(start 0.67945 -0.3048)
			(end 0.67945 0.3048)
			(stroke
				(width 0.1)
				(type default)
			)
			(layer "F.Fab")
		)
		(fp_line
			(start 0.12065 -0.2794)
			(end 0.12065 -0.3048)
			(stroke
				(width 0.1)
				(type default)
			)
			(layer "F.Fab")
		)
		(fp_line
			(start 0.12065 -0.3048)
			(end 0.67945 -0.3048)
			(stroke
				(width 0.1)
				(type default)
			)
			(layer "F.Fab")
		)
		(fp_line
			(start 0.120396 0.3048)
			(end 0.120396 0.2794)
			(stroke
				(width 0.1)
				(type default)
			)
			(layer "F.Fab")
		)
		(fp_line
			(start 0.120396 0.2794)
			(end -0.12065 0.2794)
			(stroke
				(width 0.1)
				(type default)
			)
			(layer "F.Fab")
		)
		(fp_line
			(start -0.12065 0.3048)
			(end -0.67945 0.3048)
			(stroke
				(width 0.1)
				(type default)
			)
			(layer "F.Fab")
		)
		(fp_line
			(start -0.12065 0.2794)
			(end -0.12065 0.3048)
			(stroke
				(width 0.1)
				(type default)
			)
			(layer "F.Fab")
		)
		(fp_line
			(start -0.12065 -0.2794)
			(end 0.12065 -0.2794)
			(stroke
				(width 0.1)
				(type default)
			)
			(layer "F.Fab")
		)
		(fp_line
			(start -0.12065 -0.305054)
			(end -0.12065 -0.2794)
			(stroke
				(width 0.1)
				(type default)
			)
			(layer "F.Fab")
		)
		(fp_line
			(start -0.67945 0.3048)
			(end -0.67945 -0.305054)
			(stroke
				(width 0.1)
				(type default)
			)
			(layer "F.Fab")
		)
		(fp_line
			(start -0.67945 -0.305054)
			(end -0.12065 -0.305054)
			(stroke
				(width 0.1)
				(type default)
			)
			(layer "F.Fab")
		)
		(pad "1" smd circle
			(at -0.40005 0 180)
			(size 0 0)
			(layers "F.Cu" "F.Mask" "F.Paste")
			(net "P3V3_AUX")
		)
		(pad "2" smd circle
			(at 0.40005 0 180)
			(size 0 0)
			(layers "F.Cu" "F.Mask" "F.Paste")
			(net "OCP_V3_2_PWRBRK_BUFF_N")
		)
	)
	(footprint ""
		(layer "F.Cu")
		(at 127.170434 -402.371052 -90)
		(property "Reference" "C746"
			(at 0 0 270)
			(layer "F.SilkS")
			(hide yes)
			(effects
				(font
					(size 1.27 1.27)
				)
			)
		)
		(property "Value" ""
			(at 0 0 270)
			(layer "F.Fab")
			(effects
				(font
					(size 1.27 1.27)
				)
			)
		)
		(duplicate_pad_numbers_are_jumpers no)
		(fp_line
			(start -0.299974 0.150114)
			(end -0.299974 -0.150114)
			(stroke
				(width 0.1)
				(type default)
			)
			(layer "F.Fab")
		)
		(fp_line
			(start 0.299974 0.150114)
			(end -0.299974 0.150114)
			(stroke
				(width 0.1)
				(type default)
			)
			(layer "F.Fab")
		)
		(fp_line
			(start -0.299974 -0.150114)
			(end 0.299974 -0.150114)
			(stroke
				(width 0.1)
				(type default)
			)
			(layer "F.Fab")
		)
		(fp_line
			(start 0.299974 -0.150114)
			(end 0.299974 0.150114)
			(stroke
				(width 0.1)
				(type default)
			)
			(layer "F.Fab")
		)
		(pad "1" smd rect
			(at -0.2667 0 270)
			(size 0.3048 0.381)
			(layers "F.Cu" "F.Mask" "F.Paste")
			(net "P5E_CPU1_PE2_TX_C_DN<13>")
		)
		(pad "2" smd rect
			(at 0.2667 0 270)
			(size 0.3048 0.381)
			(layers "F.Cu" "F.Mask" "F.Paste")
			(net "P5E_CPU1_PE2_TX_DN<13>")
		)
	)
)
